(kicad_sch (version 20230121) (generator eeschema)

  (paper "A3")

  (title_block
    (title "Kria K26 Devboard")
    (date "2024-03-26")
    (rev "1.2.5")
    (comment 1 "www.antmicro.com")
    (comment 2 "Antmicro Ltd.")
  )

  (junction (at 120.65 146.685) (diameter 0) (color 0 0 0 0)
  )
  (junction (at 297.815 136.525) (diameter 0) (color 0 0 0 0)
  )
  (junction (at 175.26 127.635) (diameter 0) (color 0 0 0 0)
  )
  (junction (at 156.21 140.335) (diameter 0) (color 0 0 0 0)
  )
  (junction (at 184.15 149.225) (diameter 0) (color 0 0 0 0)
  )
  (junction (at 156.21 127.635) (diameter 0) (color 0 0 0 0)
  )
  (junction (at 249.555 150.495) (diameter 0) (color 0 0 0 0)
  )
  (junction (at 120.65 149.225) (diameter 0) (color 0 0 0 0)
  )
  (junction (at 188.595 146.685) (diameter 0) (color 0 0 0 0)
  )
  (junction (at 175.26 146.685) (diameter 0) (color 0 0 0 0)
  )
  (junction (at 188.595 149.225) (diameter 0) (color 0 0 0 0)
  )
  (junction (at 273.685 144.145) (diameter 0) (color 0 0 0 0)
  )
  (junction (at 273.685 136.525) (diameter 0) (color 0 0 0 0)
  )
  (junction (at 113.665 127.635) (diameter 0) (color 0 0 0 0)
  )
  (junction (at 165.1 127.635) (diameter 0) (color 0 0 0 0)
  )

  (wire (pts (xy 128.905 153.035) (xy 128.905 154.305))
    (stroke (width 0) (type default))
  )
  (wire (pts (xy 184.15 130.175) (xy 184.15 127.635))
    (stroke (width 0) (type default))
  )
  (wire (pts (xy 268.605 150.495) (xy 268.605 151.765))
    (stroke (width 0) (type default))
  )
  (wire (pts (xy 188.595 146.685) (xy 197.485 146.685))
    (stroke (width 0) (type default))
  )
  (wire (pts (xy 124.46 142.875) (xy 130.81 142.875))
    (stroke (width 0) (type default))
  )
  (wire (pts (xy 188.595 149.225) (xy 197.485 149.225))
    (stroke (width 0) (type default))
  )
  (wire (pts (xy 267.97 139.065) (xy 266.7 139.065))
    (stroke (width 0) (type default))
  )
  (wire (pts (xy 128.27 140.335) (xy 130.81 140.335))
    (stroke (width 0) (type default))
  )
  (wire (pts (xy 235.712 139.065) (xy 251.46 139.065))
    (stroke (width 0) (type default))
  )
  (wire (pts (xy 149.86 146.685) (xy 175.26 146.685))
    (stroke (width 0) (type default))
  )
  (wire (pts (xy 267.97 139.065) (xy 267.97 136.525))
    (stroke (width 0) (type default))
  )
  (wire (pts (xy 175.26 127.635) (xy 165.1 127.635))
    (stroke (width 0) (type default))
  )
  (wire (pts (xy 273.685 144.145) (xy 273.685 142.875))
    (stroke (width 0) (type default))
  )
  (wire (pts (xy 249.555 147.955) (xy 249.555 150.495))
    (stroke (width 0) (type default))
  )
  (wire (pts (xy 266.7 144.145) (xy 273.685 144.145))
    (stroke (width 0) (type default))
  )
  (wire (pts (xy 113.665 127.635) (xy 113.665 128.905))
    (stroke (width 0) (type default))
  )
  (wire (pts (xy 188.595 150.495) (xy 188.595 149.225))
    (stroke (width 0) (type default))
  )
  (wire (pts (xy 273.685 136.525) (xy 297.815 136.525))
    (stroke (width 0) (type default))
  )
  (wire (pts (xy 235.712 141.605) (xy 251.46 141.605))
    (stroke (width 0) (type default))
  )
  (wire (pts (xy 149.86 149.225) (xy 184.15 149.225))
    (stroke (width 0) (type default))
  )
  (wire (pts (xy 120.65 149.225) (xy 120.65 150.495))
    (stroke (width 0) (type default))
  )
  (wire (pts (xy 184.15 135.255) (xy 184.15 149.225))
    (stroke (width 0) (type default))
  )
  (wire (pts (xy 156.21 135.255) (xy 156.21 140.335))
    (stroke (width 0) (type default))
  )
  (wire (pts (xy 130.81 153.035) (xy 128.905 153.035))
    (stroke (width 0) (type default))
  )
  (wire (pts (xy 128.27 127.635) (xy 128.27 140.335))
    (stroke (width 0) (type default))
  )
  (wire (pts (xy 297.815 136.525) (xy 297.815 138.43))
    (stroke (width 0) (type default))
  )
  (wire (pts (xy 267.97 136.525) (xy 273.685 136.525))
    (stroke (width 0) (type default))
  )
  (wire (pts (xy 175.26 135.255) (xy 175.26 146.685))
    (stroke (width 0) (type default))
  )
  (wire (pts (xy 120.65 146.685) (xy 130.81 146.685))
    (stroke (width 0) (type default))
  )
  (wire (pts (xy 115.57 146.685) (xy 120.65 146.685))
    (stroke (width 0) (type default))
  )
  (wire (pts (xy 156.21 127.635) (xy 165.1 127.635))
    (stroke (width 0) (type default))
  )
  (wire (pts (xy 268.605 150.495) (xy 266.7 150.495))
    (stroke (width 0) (type default))
  )
  (wire (pts (xy 249.555 150.495) (xy 251.46 150.495))
    (stroke (width 0) (type default))
  )
  (wire (pts (xy 130.81 149.225) (xy 120.65 149.225))
    (stroke (width 0) (type default))
  )
  (wire (pts (xy 120.65 145.415) (xy 120.65 146.685))
    (stroke (width 0) (type default))
  )
  (wire (pts (xy 149.86 140.335) (xy 156.21 140.335))
    (stroke (width 0) (type default))
  )
  (wire (pts (xy 297.815 136.525) (xy 302.26 136.525))
    (stroke (width 0) (type default))
  )
  (wire (pts (xy 165.1 127.635) (xy 165.1 130.175))
    (stroke (width 0) (type default))
  )
  (wire (pts (xy 184.15 149.225) (xy 188.595 149.225))
    (stroke (width 0) (type default))
  )
  (wire (pts (xy 120.65 149.225) (xy 115.57 149.225))
    (stroke (width 0) (type default))
  )
  (wire (pts (xy 249.555 150.495) (xy 249.555 151.765))
    (stroke (width 0) (type default))
  )
  (wire (pts (xy 152.4 127.635) (xy 156.21 127.635))
    (stroke (width 0) (type default))
  )
  (wire (pts (xy 156.21 140.335) (xy 156.21 151.765))
    (stroke (width 0) (type default))
  )
  (wire (pts (xy 244.475 145.415) (xy 251.46 145.415))
    (stroke (width 0) (type default))
  )
  (wire (pts (xy 188.595 145.415) (xy 188.595 146.685))
    (stroke (width 0) (type default))
  )
  (wire (pts (xy 251.46 147.955) (xy 249.555 147.955))
    (stroke (width 0) (type default))
  )
  (wire (pts (xy 273.685 136.525) (xy 273.685 137.795))
    (stroke (width 0) (type default))
  )
  (wire (pts (xy 109.855 127.635) (xy 113.665 127.635))
    (stroke (width 0) (type default))
  )
  (wire (pts (xy 184.15 127.635) (xy 175.26 127.635))
    (stroke (width 0) (type default))
  )
  (wire (pts (xy 113.665 127.635) (xy 128.27 127.635))
    (stroke (width 0) (type default))
  )
  (wire (pts (xy 273.685 144.145) (xy 280.035 144.145))
    (stroke (width 0) (type default))
  )
  (wire (pts (xy 175.26 146.685) (xy 188.595 146.685))
    (stroke (width 0) (type default))
  )
  (wire (pts (xy 156.21 127.635) (xy 156.21 130.175))
    (stroke (width 0) (type default))
  )
  (wire (pts (xy 273.685 146.685) (xy 273.685 144.145))
    (stroke (width 0) (type default))
  )
  (wire (pts (xy 175.26 130.175) (xy 175.26 127.635))
    (stroke (width 0) (type default))
  )

  (text "I2C" (at 196.215 120.65 0)
    (effects (font (size 2.54 2.54) (thickness 0.508) bold) (justify left bottom))
  )

  (label "Vref2" (at 124.46 142.875 0) (fields_autoplaced)
    (effects (font (size 1.27 1.27)) (justify left bottom))
  )
  (label "I2C_SCK_3V3" (at 235.712 139.065 0) (fields_autoplaced)
    (effects (font (size 1.27 1.27)) (justify left bottom))
  )
  (label "I2C_SDA_3V3" (at 235.712 141.605 0) (fields_autoplaced)
    (effects (font (size 1.27 1.27)) (justify left bottom))
  )
  (label "I2C_SDA_3V3" (at 157.48 149.225 0) (fields_autoplaced)
    (effects (font (size 1.27 1.27)) (justify left bottom))
  )
  (label "I2C_SCK_3V3" (at 157.48 146.685 0) (fields_autoplaced)
    (effects (font (size 1.27 1.27)) (justify left bottom))
  )
  (label "Vref2" (at 149.86 140.335 0) (fields_autoplaced)
    (effects (font (size 1.27 1.27)) (justify left bottom))
  )

  (global_label "PS_3V3" (shape input) (at 302.26 136.525 0) (fields_autoplaced)
    (effects (font (size 1.27 1.27)) (justify left))
    (property "Intersheetrefs" "${INTERSHEET_REFS}" (at 49.53 56.515 0)
      (effects (font (size 1.27 1.27)) hide)
    )
  )
  (global_label "PS_1V8" (shape input) (at 109.855 127.635 180) (fields_autoplaced)
    (effects (font (size 1.27 1.27)) (justify right))
    (property "Intersheetrefs" "${INTERSHEET_REFS}" (at 57.785 52.705 0)
      (effects (font (size 1.27 1.27)) hide)
    )
  )
  (global_label "PS_3V3" (shape input) (at 244.475 145.415 180) (fields_autoplaced)
    (effects (font (size 1.27 1.27)) (justify right))
    (property "Intersheetrefs" "${INTERSHEET_REFS}" (at 59.055 52.705 0)
      (effects (font (size 1.27 1.27)) hide)
    )
  )
  (global_label "PS_3V3" (shape input) (at 152.4 127.635 180) (fields_autoplaced)
    (effects (font (size 1.27 1.27)) (justify right))
    (property "Intersheetrefs" "${INTERSHEET_REFS}" (at 279.4 202.565 0)
      (effects (font (size 1.27 1.27)) hide)
    )
  )

  (hierarchical_label "~{EEPROM_WC}" (shape input) (at 280.035 144.145 0) (fields_autoplaced)
    (effects (font (size 1.27 1.27)) (justify left))
  )
  (hierarchical_label "I2C_SCK_3V3" (shape input) (at 197.485 146.685 0) (fields_autoplaced)
    (effects (font (size 1.27 1.27)) (justify left))
  )
  (hierarchical_label "MIO24_I2C_SCK" (shape input) (at 115.57 146.685 180) (fields_autoplaced)
    (effects (font (size 1.27 1.27)) (justify right))
  )
  (hierarchical_label "MIO25_I2C_SDA" (shape input) (at 115.57 149.225 180) (fields_autoplaced)
    (effects (font (size 1.27 1.27)) (justify right))
  )
  (hierarchical_label "I2C_SDA_3V3" (shape input) (at 197.485 149.225 0) (fields_autoplaced)
    (effects (font (size 1.27 1.27)) (justify left))
  )

  (symbol (lib_id "kria-k26-devboard:R_0R_0402") (at 273.685 146.685 270) (unit 1)
    (in_bom no) (on_board yes) (dnp yes)
    (property "Reference" "R37" (at 276.225 147.32 90)
      (effects (font (size 1.524 1.524)) (justify left))
    )
    (property "Value" "R_0R_0402" (at 260.985 167.005 0)
      (effects (font (size 1.27 1.27) (thickness 0.15)) (justify left bottom) hide)
    )
    (property "Footprint" "kria-k26-devboard-footprints:R_0402_1005Metric" (at 258.445 167.005 0)
      (effects (font (size 1.27 1.27) (thickness 0.15)) (justify left bottom) hide)
    )
    (property "Datasheet" "https://industrial.panasonic.com/cdbs/www-data/pdf/RDA0000/AOA0000C301.pdf" (at 255.905 167.005 0)
      (effects (font (size 1.27 1.27) (thickness 0.15)) (justify left bottom) hide)
    )
    (property "Manufacturer" "Panasonic" (at 250.825 167.005 0)
      (effects (font (size 1.27 1.27) (thickness 0.15)) (justify left bottom) hide)
    )
    (property "MPN" "ERJ2GE0R00X" (at 253.365 167.005 0)
      (effects (font (size 1.27 1.27) (thickness 0.15)) (justify left bottom) hide)
    )
    (property "Val" "0R" (at 276.225 149.86 90)
      (effects (font (size 1.27 1.27) (thickness 0.15)) (justify left))
    )
    (property "DNP" "DNP" (at 273.685 147.32 0)
      (effects (font (size 1.27 1.27)) (justify left))
    )
    (property "License" "Apache-2.0" (at 248.285 167.005 0)
      (effects (font (size 1.27 1.27) (thickness 0.15)) (justify left bottom) hide)
    )
    (property "Author" "Antmicro" (at 245.745 167.005 0)
      (effects (font (size 1.27 1.27) (thickness 0.15)) (justify left bottom) hide)
    )
    (property "Tolerance" "~" (at 263.525 167.005 0)
      (effects (font (size 1.27 1.27)) (justify left bottom) hide)
    )
    (property "Current" "1A" (at 243.205 167.005 0)
      (effects (font (size 1.27 1.27) (thickness 0.15)) (justify left bottom) hide)
    )
    (pin "1")
    (pin "2")
    (instances
      (project "kria-k26-devboard"
        (path ""
          (reference "R37") (unit 1)
        )
      )
    )
  )

  (symbol (lib_id "kria-k26-devboard:TP_0.75mm_SMD") (at 188.595 145.415 90) (unit 1)
    (in_bom yes) (on_board yes) (dnp no) (fields_autoplaced)
    (property "Reference" "TP8" (at 191.135 142.2399 90)
      (effects (font (size 1.27 1.27)) (justify right))
    )
    (property "Value" "TP_0.75mm_SMD" (at 196.215 127.635 0)
      (effects (font (size 1.27 1.27) (thickness 0.15)) (justify left bottom) hide)
    )
    (property "Footprint" "kria-k26-devboard-footprints:TP_SMD_0.75mm" (at 198.755 127.635 0)
      (effects (font (size 1.27 1.27) (thickness 0.15)) (justify left bottom) hide)
    )
    (property "Datasheet" "" (at 201.295 127.635 0)
      (effects (font (size 1.27 1.27) (thickness 0.15)) (justify left bottom) hide)
    )
    (property "MPN" "" (at 203.835 127.635 0)
      (effects (font (size 1.27 1.27) (thickness 0.15)) (justify left bottom) hide)
    )
    (property "Manufacturer" "" (at 206.375 127.635 0)
      (effects (font (size 1.27 1.27) (thickness 0.15)) (justify left bottom) hide)
    )
    (property "Author" "Antmicro" (at 208.915 127.635 0)
      (effects (font (size 1.27 1.27) (thickness 0.15)) (justify left bottom) hide)
    )
    (property "License" "Apache-2.0" (at 211.455 127.635 0)
      (effects (font (size 1.27 1.27) (thickness 0.15)) (justify left bottom) hide)
    )
    (pin "1")
    (instances
      (project "kria-k26-devboard"
        (path ""
          (reference "TP8") (unit 1)
        )
      )
    )
  )

  (symbol (lib_id "kria-k26-devboard:TP_0.75mm_SMD") (at 188.595 150.495 270) (unit 1)
    (in_bom yes) (on_board yes) (dnp no) (fields_autoplaced)
    (property "Reference" "TP9" (at 191.135 153.6699 90)
      (effects (font (size 1.27 1.27)) (justify left))
    )
    (property "Value" "TP_0.75mm_SMD" (at 180.975 168.275 0)
      (effects (font (size 1.27 1.27) (thickness 0.15)) (justify left bottom) hide)
    )
    (property "Footprint" "kria-k26-devboard-footprints:TP_SMD_0.75mm" (at 178.435 168.275 0)
      (effects (font (size 1.27 1.27) (thickness 0.15)) (justify left bottom) hide)
    )
    (property "Datasheet" "" (at 175.895 168.275 0)
      (effects (font (size 1.27 1.27) (thickness 0.15)) (justify left bottom) hide)
    )
    (property "MPN" "" (at 173.355 168.275 0)
      (effects (font (size 1.27 1.27) (thickness 0.15)) (justify left bottom) hide)
    )
    (property "Manufacturer" "" (at 170.815 168.275 0)
      (effects (font (size 1.27 1.27) (thickness 0.15)) (justify left bottom) hide)
    )
    (property "Author" "Antmicro" (at 168.275 168.275 0)
      (effects (font (size 1.27 1.27) (thickness 0.15)) (justify left bottom) hide)
    )
    (property "License" "Apache-2.0" (at 165.735 168.275 0)
      (effects (font (size 1.27 1.27) (thickness 0.15)) (justify left bottom) hide)
    )
    (pin "1")
    (instances
      (project "kria-k26-devboard"
        (path ""
          (reference "TP9") (unit 1)
        )
      )
    )
  )

  (symbol (lib_id "kria-k26-devboard:GND") (at 273.685 151.765 0) (unit 1)
    (in_bom yes) (on_board yes) (dnp no) (fields_autoplaced)
    (property "Reference" "#PWR062" (at 273.685 158.115 0)
      (effects (font (size 1.27 1.27)) hide)
    )
    (property "Value" "GND" (at 273.685 156.845 0)
      (effects (font (size 1.27 1.27)))
    )
    (property "Footprint" "" (at 282.575 159.385 0)
      (effects (font (size 1.27 1.27) (thickness 0.15)) (justify left bottom) hide)
    )
    (property "Datasheet" "" (at 282.575 164.465 0)
      (effects (font (size 1.27 1.27) (thickness 0.15)) (justify left bottom) hide)
    )
    (property "Author" "Antmicro" (at 282.575 159.385 0)
      (effects (font (size 1.27 1.27) (thickness 0.15)) (justify left bottom) hide)
    )
    (property "License" "Apache-2.0" (at 282.575 161.925 0)
      (effects (font (size 1.27 1.27) (thickness 0.15)) (justify left bottom) hide)
    )
    (pin "1")
    (instances
      (project "kria-k26-devboard"
        (path ""
          (reference "#PWR062") (unit 1)
        )
      )
    )
  )

  (symbol (lib_id "kria-k26-devboard:M24C64-F_DFN8") (at 251.46 139.065 0) (unit 1)
    (in_bom yes) (on_board yes) (dnp no)
    (property "Reference" "U13" (at 259.08 132.08 0)
      (effects (font (size 1.524 1.524)))
    )
    (property "Value" "M24C64-F_DFN8" (at 259.08 133.985 0)
      (effects (font (size 1.27 1.27) (thickness 0.15)) hide)
    )
    (property "Footprint" "kria-k26-devboard-footprints:DFN-8-1EP_3x2mm_P0.5mm_EP1.36x1.46mm" (at 289.56 146.685 0)
      (effects (font (size 1.27 1.27) (thickness 0.15)) (justify left bottom) hide)
    )
    (property "Datasheet" "https://eu.mouser.com/datasheet/2/389/cd00259166-1797197.pdf" (at 289.56 149.225 0)
      (effects (font (size 1.27 1.27) (thickness 0.15)) (justify left bottom) hide)
    )
    (property "Manufacturer" "STMicroelectronics" (at 289.56 151.765 0)
      (effects (font (size 1.27 1.27) (thickness 0.15)) (justify left bottom) hide)
    )
    (property "MPN" "M24C64-FMC6TG" (at 259.08 134.62 0)
      (effects (font (size 1.27 1.27) (thickness 0.15)))
    )
    (property "Author" "Antmicro" (at 289.56 156.845 0)
      (effects (font (size 1.27 1.27) (thickness 0.15)) (justify left bottom) hide)
    )
    (property "License" "Apache-2.0" (at 289.56 159.385 0)
      (effects (font (size 1.27 1.27) (thickness 0.15)) (justify left bottom) hide)
    )
    (pin "1")
    (pin "2")
    (pin "3")
    (pin "4")
    (pin "5")
    (pin "6")
    (pin "7")
    (pin "8")
    (pin "9")
    (instances
      (project "kria-k26-devboard"
        (path ""
          (reference "U13") (unit 1)
        )
      )
    )
  )

  (symbol (lib_id "kria-k26-devboard:PCA9306D_SOIC") (at 130.81 140.335 0) (unit 1)
    (in_bom yes) (on_board yes) (dnp no)
    (property "Reference" "U12" (at 140.335 133.35 0)
      (effects (font (size 1.524 1.524)))
    )
    (property "Value" "PCA9306D_SOIC" (at 163.83 146.685 0)
      (effects (font (size 1.27 1.27) (thickness 0.15)) (justify left bottom) hide)
    )
    (property "Footprint" "kria-k26-devboard-footprints:SOIC-8_3.9x4.9x1.75mm_P1.27mm" (at 163.83 149.225 0)
      (effects (font (size 1.27 1.27) (thickness 0.15)) (justify left bottom) hide)
    )
    (property "Datasheet" "https://www.nxp.com/docs/en/data-sheet/PCA9306.pdf" (at 163.83 151.765 0)
      (effects (font (size 1.27 1.27) (thickness 0.15)) (justify left bottom) hide)
    )
    (property "MPN" "PCA9306D,118" (at 140.335 135.89 0)
      (effects (font (size 1.27 1.27) (thickness 0.15)))
    )
    (property "Manufacturer" "NXP" (at 163.83 156.845 0)
      (effects (font (size 1.27 1.27) (thickness 0.15)) (justify left bottom) hide)
    )
    (property "Author" "Antmicro" (at 163.83 159.385 0)
      (effects (font (size 1.27 1.27) (thickness 0.15)) (justify left bottom) hide)
    )
    (property "License" "Apache-2.0" (at 163.83 161.925 0)
      (effects (font (size 1.27 1.27) (thickness 0.15)) (justify left bottom) hide)
    )
    (pin "1")
    (pin "2")
    (pin "3")
    (pin "4")
    (pin "5")
    (pin "6")
    (pin "7")
    (pin "8")
    (instances
      (project "kria-k26-devboard"
        (path ""
          (reference "U12") (unit 1)
        )
      )
    )
  )

  (symbol (lib_id "kria-k26-devboard:C_100n_0402") (at 113.665 128.905 270) (unit 1)
    (in_bom yes) (on_board yes) (dnp no) (fields_autoplaced)
    (property "Reference" "C32" (at 116.84 130.1813 90)
      (effects (font (size 1.524 1.524)) (justify left))
    )
    (property "Value" "C_100n_0402" (at 103.505 149.225 0)
      (effects (font (size 1.27 1.27) (thickness 0.15)) (justify left bottom) hide)
    )
    (property "Footprint" "kria-k26-devboard-footprints:C_0402_1005Metric" (at 100.965 149.225 0)
      (effects (font (size 1.27 1.27) (thickness 0.15)) (justify left bottom) hide)
    )
    (property "Datasheet" "https://search.murata.co.jp/Ceramy/image/img/A01X/G101/ENG/GRM155R61H104KE14-01.pdf" (at 98.425 149.225 0)
      (effects (font (size 1.27 1.27) (thickness 0.15)) (justify left bottom) hide)
    )
    (property "Manufacturer" "Murata" (at 93.345 149.225 0)
      (effects (font (size 1.27 1.27) (thickness 0.15)) (justify left bottom) hide)
    )
    (property "MPN" "GRM155R61H104KE14D" (at 95.885 149.225 0)
      (effects (font (size 1.27 1.27) (thickness 0.15)) (justify left bottom) hide)
    )
    (property "Val" "100n" (at 116.84 133.3562 90)
      (effects (font (size 1.27 1.27) (thickness 0.15)) (justify left))
    )
    (property "License" "Apache-2.0" (at 90.805 149.225 0)
      (effects (font (size 1.27 1.27) (thickness 0.15)) (justify left bottom) hide)
    )
    (property "Author" "Antmicro" (at 88.265 149.225 0)
      (effects (font (size 1.27 1.27) (thickness 0.15)) (justify left bottom) hide)
    )
    (property "Voltage" "50V" (at 85.725 149.225 0)
      (effects (font (size 1.27 1.27)) (justify left bottom) hide)
    )
    (property "Dielectric" "X5R" (at 83.185 149.225 0)
      (effects (font (size 1.27 1.27)) (justify left bottom) hide)
    )
    (pin "1")
    (pin "2")
    (instances
      (project "kria-k26-devboard"
        (path ""
          (reference "C32") (unit 1)
        )
      )
    )
  )

  (symbol (lib_id "kria-k26-devboard:GND") (at 113.665 133.985 0) (unit 1)
    (in_bom yes) (on_board yes) (dnp no) (fields_autoplaced)
    (property "Reference" "#PWR056" (at 113.665 140.335 0)
      (effects (font (size 1.27 1.27)) hide)
    )
    (property "Value" "GND" (at 111.125 135.2549 0)
      (effects (font (size 1.27 1.27)) (justify right))
    )
    (property "Footprint" "" (at 122.555 141.605 0)
      (effects (font (size 1.27 1.27) (thickness 0.15)) (justify left bottom) hide)
    )
    (property "Datasheet" "" (at 122.555 146.685 0)
      (effects (font (size 1.27 1.27) (thickness 0.15)) (justify left bottom) hide)
    )
    (property "Author" "Antmicro" (at 122.555 141.605 0)
      (effects (font (size 1.27 1.27) (thickness 0.15)) (justify left bottom) hide)
    )
    (property "License" "Apache-2.0" (at 122.555 144.145 0)
      (effects (font (size 1.27 1.27) (thickness 0.15)) (justify left bottom) hide)
    )
    (pin "1")
    (instances
      (project "kria-k26-devboard"
        (path ""
          (reference "#PWR056") (unit 1)
        )
      )
    )
  )

  (symbol (lib_id "kria-k26-devboard:C_100n_0402") (at 165.1 130.175 90) (mirror x) (unit 1)
    (in_bom yes) (on_board yes) (dnp no) (fields_autoplaced)
    (property "Reference" "C34" (at 167.64 131.4513 90)
      (effects (font (size 1.524 1.524)) (justify right))
    )
    (property "Value" "C_100n_0402" (at 175.26 150.495 0)
      (effects (font (size 1.27 1.27) (thickness 0.15)) (justify left bottom) hide)
    )
    (property "Footprint" "kria-k26-devboard-footprints:C_0402_1005Metric" (at 177.8 150.495 0)
      (effects (font (size 1.27 1.27) (thickness 0.15)) (justify left bottom) hide)
    )
    (property "Datasheet" "https://search.murata.co.jp/Ceramy/image/img/A01X/G101/ENG/GRM155R61H104KE14-01.pdf" (at 180.34 150.495 0)
      (effects (font (size 1.27 1.27) (thickness 0.15)) (justify left bottom) hide)
    )
    (property "Manufacturer" "Murata" (at 185.42 150.495 0)
      (effects (font (size 1.27 1.27) (thickness 0.15)) (justify left bottom) hide)
    )
    (property "MPN" "GRM155R61H104KE14D" (at 182.88 150.495 0)
      (effects (font (size 1.27 1.27) (thickness 0.15)) (justify left bottom) hide)
    )
    (property "Val" "100n" (at 167.64 134.6262 90)
      (effects (font (size 1.27 1.27) (thickness 0.15)) (justify right))
    )
    (property "License" "Apache-2.0" (at 187.96 150.495 0)
      (effects (font (size 1.27 1.27) (thickness 0.15)) (justify left bottom) hide)
    )
    (property "Author" "Antmicro" (at 190.5 150.495 0)
      (effects (font (size 1.27 1.27) (thickness 0.15)) (justify left bottom) hide)
    )
    (property "Voltage" "50V" (at 193.04 150.495 0)
      (effects (font (size 1.27 1.27)) (justify left bottom) hide)
    )
    (property "Dielectric" "X5R" (at 195.58 150.495 0)
      (effects (font (size 1.27 1.27)) (justify left bottom) hide)
    )
    (pin "1")
    (pin "2")
    (instances
      (project "kria-k26-devboard"
        (path ""
          (reference "C34") (unit 1)
        )
      )
    )
  )

  (symbol (lib_id "kria-k26-devboard:GND") (at 165.1 135.255 0) (unit 1)
    (in_bom yes) (on_board yes) (dnp no) (fields_autoplaced)
    (property "Reference" "#PWR059" (at 165.1 141.605 0)
      (effects (font (size 1.27 1.27)) hide)
    )
    (property "Value" "GND" (at 165.1 140.589 0)
      (effects (font (size 1.27 1.27)))
    )
    (property "Footprint" "" (at 173.99 142.875 0)
      (effects (font (size 1.27 1.27) (thickness 0.15)) (justify left bottom) hide)
    )
    (property "Datasheet" "" (at 173.99 147.955 0)
      (effects (font (size 1.27 1.27) (thickness 0.15)) (justify left bottom) hide)
    )
    (property "Author" "Antmicro" (at 173.99 142.875 0)
      (effects (font (size 1.27 1.27) (thickness 0.15)) (justify left bottom) hide)
    )
    (property "License" "Apache-2.0" (at 173.99 145.415 0)
      (effects (font (size 1.27 1.27) (thickness 0.15)) (justify left bottom) hide)
    )
    (pin "1")
    (instances
      (project "kria-k26-devboard"
        (path ""
          (reference "#PWR059") (unit 1)
        )
      )
    )
  )

  (symbol (lib_id "kria-k26-devboard:R_200k_0402") (at 156.21 130.175 90) (mirror x) (unit 1)
    (in_bom yes) (on_board yes) (dnp no) (fields_autoplaced)
    (property "Reference" "R33" (at 158.75 131.445 90)
      (effects (font (size 1.524 1.524)) (justify right))
    )
    (property "Value" "R_200k_0402" (at 168.91 150.495 0)
      (effects (font (size 1.27 1.27) (thickness 0.15)) (justify left bottom) hide)
    )
    (property "Footprint" "kria-k26-devboard-footprints:R_0402_1005Metric" (at 171.45 150.495 0)
      (effects (font (size 1.27 1.27) (thickness 0.15)) (justify left bottom) hide)
    )
    (property "Datasheet" "https://www.bourns.com/docs/product-datasheets/cr.pdf" (at 173.99 150.495 0)
      (effects (font (size 1.27 1.27) (thickness 0.15)) (justify left bottom) hide)
    )
    (property "Manufacturer" "Bourns" (at 179.07 150.495 0)
      (effects (font (size 1.27 1.27) (thickness 0.15)) (justify left bottom) hide)
    )
    (property "MPN" "CR0402-FX-2003GLF" (at 176.53 150.495 0)
      (effects (font (size 1.27 1.27) (thickness 0.15)) (justify left bottom) hide)
    )
    (property "Val" "200k" (at 158.75 134.6199 90)
      (effects (font (size 1.27 1.27) (thickness 0.15)) (justify right))
    )
    (property "License" "Apache-2.0" (at 181.61 150.495 0)
      (effects (font (size 1.27 1.27) (thickness 0.15)) (justify left bottom) hide)
    )
    (property "Author" "Antmicro" (at 184.15 150.495 0)
      (effects (font (size 1.27 1.27) (thickness 0.15)) (justify left bottom) hide)
    )
    (property "Tolerance" "1%" (at 166.37 150.495 0)
      (effects (font (size 1.27 1.27)) (justify left bottom) hide)
    )
    (pin "1")
    (pin "2")
    (instances
      (project "kria-k26-devboard"
        (path ""
          (reference "R33") (unit 1)
        )
      )
    )
  )

  (symbol (lib_id "kria-k26-devboard:GND") (at 128.905 154.305 0) (unit 1)
    (in_bom yes) (on_board yes) (dnp no) (fields_autoplaced)
    (property "Reference" "#PWR057" (at 128.905 160.655 0)
      (effects (font (size 1.27 1.27)) hide)
    )
    (property "Value" "GND" (at 128.905 159.385 0)
      (effects (font (size 1.27 1.27)))
    )
    (property "Footprint" "" (at 137.795 161.925 0)
      (effects (font (size 1.27 1.27) (thickness 0.15)) (justify left bottom) hide)
    )
    (property "Datasheet" "" (at 137.795 167.005 0)
      (effects (font (size 1.27 1.27) (thickness 0.15)) (justify left bottom) hide)
    )
    (property "Author" "Antmicro" (at 137.795 161.925 0)
      (effects (font (size 1.27 1.27) (thickness 0.15)) (justify left bottom) hide)
    )
    (property "License" "Apache-2.0" (at 137.795 164.465 0)
      (effects (font (size 1.27 1.27) (thickness 0.15)) (justify left bottom) hide)
    )
    (pin "1")
    (instances
      (project "kria-k26-devboard"
        (path ""
          (reference "#PWR057") (unit 1)
        )
      )
    )
  )

  (symbol (lib_id "kria-k26-devboard:C_100p_0402") (at 156.21 151.765 270) (unit 1)
    (in_bom yes) (on_board yes) (dnp no) (fields_autoplaced)
    (property "Reference" "C33" (at 158.75 153.0413 90)
      (effects (font (size 1.524 1.524)) (justify left))
    )
    (property "Value" "C_100p_0402" (at 146.05 172.085 0)
      (effects (font (size 1.27 1.27) (thickness 0.15)) (justify left bottom) hide)
    )
    (property "Footprint" "kria-k26-devboard-footprints:C_0402_1005Metric" (at 143.51 172.085 0)
      (effects (font (size 1.27 1.27) (thickness 0.15)) (justify left bottom) hide)
    )
    (property "Datasheet" "https://www.murata.com/-/media/webrenewal/support/library/catalog/products/k35e.ashx?la=en-us&cvid=20200508021757000000" (at 140.97 172.085 0)
      (effects (font (size 1.27 1.27) (thickness 0.15)) (justify left bottom) hide)
    )
    (property "Manufacturer" "Murata" (at 135.89 172.085 0)
      (effects (font (size 1.27 1.27) (thickness 0.15)) (justify left bottom) hide)
    )
    (property "MPN" "GCM1555C1H101JA16D" (at 138.43 172.085 0)
      (effects (font (size 1.27 1.27) (thickness 0.15)) (justify left bottom) hide)
    )
    (property "Val" "100p" (at 158.75 156.2162 90)
      (effects (font (size 1.27 1.27) (thickness 0.15)) (justify left))
    )
    (property "License" "Apache-2.0" (at 133.35 172.085 0)
      (effects (font (size 1.27 1.27) (thickness 0.15)) (justify left bottom) hide)
    )
    (property "Author" "Antmicro" (at 130.81 172.085 0)
      (effects (font (size 1.27 1.27) (thickness 0.15)) (justify left bottom) hide)
    )
    (property "Voltage" "50V" (at 128.27 172.085 0)
      (effects (font (size 1.27 1.27)) (justify left bottom) hide)
    )
    (property "Dielectric" "C0G" (at 125.73 172.085 0)
      (effects (font (size 1.27 1.27)) (justify left bottom) hide)
    )
    (pin "1")
    (pin "2")
    (instances
      (project "kria-k26-devboard"
        (path ""
          (reference "C33") (unit 1)
        )
      )
    )
  )

  (symbol (lib_id "kria-k26-devboard:GND") (at 156.21 156.845 0) (unit 1)
    (in_bom yes) (on_board yes) (dnp no) (fields_autoplaced)
    (property "Reference" "#PWR058" (at 156.21 163.195 0)
      (effects (font (size 1.27 1.27)) hide)
    )
    (property "Value" "GND" (at 156.21 161.925 0)
      (effects (font (size 1.27 1.27)))
    )
    (property "Footprint" "" (at 165.1 164.465 0)
      (effects (font (size 1.27 1.27) (thickness 0.15)) (justify left bottom) hide)
    )
    (property "Datasheet" "" (at 165.1 169.545 0)
      (effects (font (size 1.27 1.27) (thickness 0.15)) (justify left bottom) hide)
    )
    (property "Author" "Antmicro" (at 165.1 164.465 0)
      (effects (font (size 1.27 1.27) (thickness 0.15)) (justify left bottom) hide)
    )
    (property "License" "Apache-2.0" (at 165.1 167.005 0)
      (effects (font (size 1.27 1.27) (thickness 0.15)) (justify left bottom) hide)
    )
    (pin "1")
    (instances
      (project "kria-k26-devboard"
        (path ""
          (reference "#PWR058") (unit 1)
        )
      )
    )
  )

  (symbol (lib_id "kria-k26-devboard:R_2k2_0402") (at 175.26 130.175 270) (unit 1)
    (in_bom yes) (on_board yes) (dnp no) (fields_autoplaced)
    (property "Reference" "R34" (at 177.8 131.445 90)
      (effects (font (size 1.524 1.524)) (justify left))
    )
    (property "Value" "R_2k2_0402" (at 162.56 150.495 0)
      (effects (font (size 1.27 1.27) (thickness 0.15)) (justify left bottom) hide)
    )
    (property "Footprint" "kria-k26-devboard-footprints:R_0402_1005Metric" (at 160.02 150.495 0)
      (effects (font (size 1.27 1.27) (thickness 0.15)) (justify left bottom) hide)
    )
    (property "Datasheet" "https://www.bourns.com/docs/product-datasheets/cr.pdf" (at 157.48 150.495 0)
      (effects (font (size 1.27 1.27) (thickness 0.15)) (justify left bottom) hide)
    )
    (property "Manufacturer" "Bourns" (at 152.4 150.495 0)
      (effects (font (size 1.27 1.27) (thickness 0.15)) (justify left bottom) hide)
    )
    (property "MPN" "CR0402-FX-2201GLF" (at 154.94 150.495 0)
      (effects (font (size 1.27 1.27) (thickness 0.15)) (justify left bottom) hide)
    )
    (property "Val" "2k2" (at 177.8 134.6199 90)
      (effects (font (size 1.27 1.27) (thickness 0.15)) (justify left))
    )
    (property "License" "Apache-2.0" (at 149.86 150.495 0)
      (effects (font (size 1.27 1.27) (thickness 0.15)) (justify left bottom) hide)
    )
    (property "Author" "Antmicro" (at 147.32 150.495 0)
      (effects (font (size 1.27 1.27) (thickness 0.15)) (justify left bottom) hide)
    )
    (property "Tolerance" "1%" (at 165.1 150.495 0)
      (effects (font (size 1.27 1.27)) (justify left bottom) hide)
    )
    (pin "1")
    (pin "2")
    (instances
      (project "kria-k26-devboard"
        (path ""
          (reference "R34") (unit 1)
        )
      )
    )
  )

  (symbol (lib_id "kria-k26-devboard:R_2k2_0402") (at 184.15 130.175 270) (unit 1)
    (in_bom yes) (on_board yes) (dnp no) (fields_autoplaced)
    (property "Reference" "R35" (at 186.69 131.445 90)
      (effects (font (size 1.524 1.524)) (justify left))
    )
    (property "Value" "R_2k2_0402" (at 171.45 150.495 0)
      (effects (font (size 1.27 1.27) (thickness 0.15)) (justify left bottom) hide)
    )
    (property "Footprint" "kria-k26-devboard-footprints:R_0402_1005Metric" (at 168.91 150.495 0)
      (effects (font (size 1.27 1.27) (thickness 0.15)) (justify left bottom) hide)
    )
    (property "Datasheet" "https://www.bourns.com/docs/product-datasheets/cr.pdf" (at 166.37 150.495 0)
      (effects (font (size 1.27 1.27) (thickness 0.15)) (justify left bottom) hide)
    )
    (property "Manufacturer" "Bourns" (at 161.29 150.495 0)
      (effects (font (size 1.27 1.27) (thickness 0.15)) (justify left bottom) hide)
    )
    (property "MPN" "CR0402-FX-2201GLF" (at 163.83 150.495 0)
      (effects (font (size 1.27 1.27) (thickness 0.15)) (justify left bottom) hide)
    )
    (property "Val" "2k2" (at 186.69 134.6199 90)
      (effects (font (size 1.27 1.27) (thickness 0.15)) (justify left))
    )
    (property "License" "Apache-2.0" (at 158.75 150.495 0)
      (effects (font (size 1.27 1.27) (thickness 0.15)) (justify left bottom) hide)
    )
    (property "Author" "Antmicro" (at 156.21 150.495 0)
      (effects (font (size 1.27 1.27) (thickness 0.15)) (justify left bottom) hide)
    )
    (property "Tolerance" "1%" (at 173.99 150.495 0)
      (effects (font (size 1.27 1.27)) (justify left bottom) hide)
    )
    (pin "1")
    (pin "2")
    (instances
      (project "kria-k26-devboard"
        (path ""
          (reference "R35") (unit 1)
        )
      )
    )
  )

  (symbol (lib_id "kria-k26-devboard:GND") (at 268.605 151.765 0) (unit 1)
    (in_bom yes) (on_board yes) (dnp no) (fields_autoplaced)
    (property "Reference" "#PWR061" (at 268.605 158.115 0)
      (effects (font (size 1.27 1.27)) hide)
    )
    (property "Value" "GND" (at 268.605 156.845 0)
      (effects (font (size 1.27 1.27)))
    )
    (property "Footprint" "" (at 277.495 159.385 0)
      (effects (font (size 1.27 1.27) (thickness 0.15)) (justify left bottom) hide)
    )
    (property "Datasheet" "" (at 277.495 164.465 0)
      (effects (font (size 1.27 1.27) (thickness 0.15)) (justify left bottom) hide)
    )
    (property "Author" "Antmicro" (at 277.495 159.385 0)
      (effects (font (size 1.27 1.27) (thickness 0.15)) (justify left bottom) hide)
    )
    (property "License" "Apache-2.0" (at 277.495 161.925 0)
      (effects (font (size 1.27 1.27) (thickness 0.15)) (justify left bottom) hide)
    )
    (pin "1")
    (instances
      (project "kria-k26-devboard"
        (path ""
          (reference "#PWR061") (unit 1)
        )
      )
    )
  )

  (symbol (lib_id "kria-k26-devboard:GND") (at 249.555 151.765 0) (unit 1)
    (in_bom yes) (on_board yes) (dnp no) (fields_autoplaced)
    (property "Reference" "#PWR060" (at 249.555 158.115 0)
      (effects (font (size 1.27 1.27)) hide)
    )
    (property "Value" "GND" (at 249.555 156.845 0)
      (effects (font (size 1.27 1.27)))
    )
    (property "Footprint" "" (at 258.445 159.385 0)
      (effects (font (size 1.27 1.27) (thickness 0.15)) (justify left bottom) hide)
    )
    (property "Datasheet" "" (at 258.445 164.465 0)
      (effects (font (size 1.27 1.27) (thickness 0.15)) (justify left bottom) hide)
    )
    (property "Author" "Antmicro" (at 258.445 159.385 0)
      (effects (font (size 1.27 1.27) (thickness 0.15)) (justify left bottom) hide)
    )
    (property "License" "Apache-2.0" (at 258.445 161.925 0)
      (effects (font (size 1.27 1.27) (thickness 0.15)) (justify left bottom) hide)
    )
    (pin "1")
    (instances
      (project "kria-k26-devboard"
        (path ""
          (reference "#PWR060") (unit 1)
        )
      )
    )
  )

  (symbol (lib_id "kria-k26-devboard:R_1k_0402") (at 273.685 137.795 270) (unit 1)
    (in_bom yes) (on_board yes) (dnp no)
    (property "Reference" "R36" (at 276.225 139.065 90)
      (effects (font (size 1.524 1.524)) (justify left))
    )
    (property "Value" "R_1k_0402" (at 260.985 158.115 0)
      (effects (font (size 1.27 1.27) (thickness 0.15)) (justify left bottom) hide)
    )
    (property "Footprint" "kria-k26-devboard-footprints:R_0402_1005Metric" (at 258.445 158.115 0)
      (effects (font (size 1.27 1.27) (thickness 0.15)) (justify left bottom) hide)
    )
    (property "Datasheet" "https://www.bourns.com/docs/product-datasheets/cr.pdf" (at 255.905 158.115 0)
      (effects (font (size 1.27 1.27) (thickness 0.15)) (justify left bottom) hide)
    )
    (property "Manufacturer" "Bourns" (at 250.825 158.115 0)
      (effects (font (size 1.27 1.27) (thickness 0.15)) (justify left bottom) hide)
    )
    (property "MPN" "CR0402-FX-1001GLF" (at 253.365 158.115 0)
      (effects (font (size 1.27 1.27) (thickness 0.15)) (justify left bottom) hide)
    )
    (property "Val" "1k" (at 276.225 141.605 90)
      (effects (font (size 1.27 1.27) (thickness 0.15)) (justify left))
    )
    (property "License" "Apache-2.0" (at 248.285 158.115 0)
      (effects (font (size 1.27 1.27) (thickness 0.15)) (justify left bottom) hide)
    )
    (property "Author" "Antmicro" (at 245.745 158.115 0)
      (effects (font (size 1.27 1.27) (thickness 0.15)) (justify left bottom) hide)
    )
    (property "Tolerance" "1%" (at 263.525 158.115 0)
      (effects (font (size 1.27 1.27)) (justify left bottom) hide)
    )
    (pin "1")
    (pin "2")
    (instances
      (project "kria-k26-devboard"
        (path ""
          (reference "R36") (unit 1)
        )
      )
    )
  )

  (symbol (lib_id "kria-k26-devboard:C_100n_0402") (at 297.815 138.43 270) (unit 1)
    (in_bom yes) (on_board yes) (dnp no) (fields_autoplaced)
    (property "Reference" "C35" (at 300.99 139.7063 90)
      (effects (font (size 1.524 1.524)) (justify left))
    )
    (property "Value" "C_100n_0402" (at 287.655 158.75 0)
      (effects (font (size 1.27 1.27) (thickness 0.15)) (justify left bottom) hide)
    )
    (property "Footprint" "kria-k26-devboard-footprints:C_0402_1005Metric" (at 285.115 158.75 0)
      (effects (font (size 1.27 1.27) (thickness 0.15)) (justify left bottom) hide)
    )
    (property "Datasheet" "https://search.murata.co.jp/Ceramy/image/img/A01X/G101/ENG/GRM155R61H104KE14-01.pdf" (at 282.575 158.75 0)
      (effects (font (size 1.27 1.27) (thickness 0.15)) (justify left bottom) hide)
    )
    (property "Manufacturer" "Murata" (at 277.495 158.75 0)
      (effects (font (size 1.27 1.27) (thickness 0.15)) (justify left bottom) hide)
    )
    (property "MPN" "GRM155R61H104KE14D" (at 280.035 158.75 0)
      (effects (font (size 1.27 1.27) (thickness 0.15)) (justify left bottom) hide)
    )
    (property "Val" "100n" (at 300.99 142.8812 90)
      (effects (font (size 1.27 1.27) (thickness 0.15)) (justify left))
    )
    (property "License" "Apache-2.0" (at 274.955 158.75 0)
      (effects (font (size 1.27 1.27) (thickness 0.15)) (justify left bottom) hide)
    )
    (property "Author" "Antmicro" (at 272.415 158.75 0)
      (effects (font (size 1.27 1.27) (thickness 0.15)) (justify left bottom) hide)
    )
    (property "Voltage" "50V" (at 269.875 158.75 0)
      (effects (font (size 1.27 1.27)) (justify left bottom) hide)
    )
    (property "Dielectric" "X5R" (at 267.335 158.75 0)
      (effects (font (size 1.27 1.27)) (justify left bottom) hide)
    )
    (pin "1")
    (pin "2")
    (instances
      (project "kria-k26-devboard"
        (path ""
          (reference "C35") (unit 1)
        )
      )
    )
  )

  (symbol (lib_id "kria-k26-devboard:GND") (at 297.815 143.51 0) (unit 1)
    (in_bom yes) (on_board yes) (dnp no) (fields_autoplaced)
    (property "Reference" "#PWR063" (at 297.815 149.86 0)
      (effects (font (size 1.27 1.27)) hide)
    )
    (property "Value" "GND" (at 297.815 148.59 0)
      (effects (font (size 1.27 1.27)))
    )
    (property "Footprint" "" (at 306.705 151.13 0)
      (effects (font (size 1.27 1.27) (thickness 0.15)) (justify left bottom) hide)
    )
    (property "Datasheet" "" (at 306.705 156.21 0)
      (effects (font (size 1.27 1.27) (thickness 0.15)) (justify left bottom) hide)
    )
    (property "Author" "Antmicro" (at 306.705 151.13 0)
      (effects (font (size 1.27 1.27) (thickness 0.15)) (justify left bottom) hide)
    )
    (property "License" "Apache-2.0" (at 306.705 153.67 0)
      (effects (font (size 1.27 1.27) (thickness 0.15)) (justify left bottom) hide)
    )
    (pin "1")
    (instances
      (project "kria-k26-devboard"
        (path ""
          (reference "#PWR063") (unit 1)
        )
      )
    )
  )

  (symbol (lib_id "kria-k26-devboard:TP_0.75mm_SMD") (at 120.65 150.495 270) (unit 1)
    (in_bom yes) (on_board yes) (dnp no)
    (property "Reference" "TP62" (at 123.19 156.21 90)
      (effects (font (size 1.27 1.27)) (justify right))
    )
    (property "Value" "TP_0.75mm_SMD" (at 113.03 168.275 0)
      (effects (font (size 1.27 1.27) (thickness 0.15)) (justify left bottom) hide)
    )
    (property "Footprint" "kria-k26-devboard-footprints:TP_SMD_0.75mm" (at 110.49 168.275 0)
      (effects (font (size 1.27 1.27) (thickness 0.15)) (justify left bottom) hide)
    )
    (property "Datasheet" "" (at 107.95 168.275 0)
      (effects (font (size 1.27 1.27) (thickness 0.15)) (justify left bottom) hide)
    )
    (property "MPN" "" (at 105.41 168.275 0)
      (effects (font (size 1.27 1.27) (thickness 0.15)) (justify left bottom) hide)
    )
    (property "Manufacturer" "" (at 102.87 168.275 0)
      (effects (font (size 1.27 1.27) (thickness 0.15)) (justify left bottom) hide)
    )
    (property "Author" "Antmicro" (at 100.33 168.275 0)
      (effects (font (size 1.27 1.27) (thickness 0.15)) (justify left bottom) hide)
    )
    (property "License" "Apache-2.0" (at 97.79 168.275 0)
      (effects (font (size 1.27 1.27) (thickness 0.15)) (justify left bottom) hide)
    )
    (pin "1")
    (instances
      (project "kria-k26-devboard"
        (path ""
          (reference "TP62") (unit 1)
        )
      )
    )
  )

  (symbol (lib_id "kria-k26-devboard:TP_0.75mm_SMD") (at 120.65 145.415 90) (unit 1)
    (in_bom yes) (on_board yes) (dnp no)
    (property "Reference" "TP61" (at 118.745 140.335 90)
      (effects (font (size 1.27 1.27)) (justify right))
    )
    (property "Value" "TP_0.75mm_SMD" (at 128.27 127.635 0)
      (effects (font (size 1.27 1.27) (thickness 0.15)) (justify left bottom) hide)
    )
    (property "Footprint" "kria-k26-devboard-footprints:TP_SMD_0.75mm" (at 130.81 127.635 0)
      (effects (font (size 1.27 1.27) (thickness 0.15)) (justify left bottom) hide)
    )
    (property "Datasheet" "" (at 133.35 127.635 0)
      (effects (font (size 1.27 1.27) (thickness 0.15)) (justify left bottom) hide)
    )
    (property "MPN" "" (at 135.89 127.635 0)
      (effects (font (size 1.27 1.27) (thickness 0.15)) (justify left bottom) hide)
    )
    (property "Manufacturer" "" (at 138.43 127.635 0)
      (effects (font (size 1.27 1.27) (thickness 0.15)) (justify left bottom) hide)
    )
    (property "Author" "Antmicro" (at 140.97 127.635 0)
      (effects (font (size 1.27 1.27) (thickness 0.15)) (justify left bottom) hide)
    )
    (property "License" "Apache-2.0" (at 143.51 127.635 0)
      (effects (font (size 1.27 1.27) (thickness 0.15)) (justify left bottom) hide)
    )
    (pin "1")
    (instances
      (project "kria-k26-devboard"
        (path ""
          (reference "TP61") (unit 1)
        )
      )
    )
  )
)
